(kicad_pcb
	(version 20260206)
	(generator "pcbnew")
	(generator_version "10.0")
	(general
		(thickness 1.6)
		(legacy_teardrops no)
	)
	(paper "A4")
	(title_block
		(title "04192023_DAF0TMB3IC0_F0TG_MB_C_brd_V02_OCP.brd")
		(comment 1 "Grand Teton / footprints 4562-4569 of 8354")
	)
	(layers
		(0 "F.Cu" signal "TOP")
		(4 "In1.Cu" signal "GND")
		(6 "In2.Cu" signal "IN1")
		(8 "In3.Cu" signal "GND1")
		(10 "In4.Cu" signal "IN2")
		(12 "In5.Cu" signal "GND2")
		(14 "In6.Cu" signal "IN3")
		(16 "In7.Cu" signal "GND3")
		(18 "In8.Cu" signal "VCC")
		(20 "In9.Cu" signal "VCC1")
		(22 "In10.Cu" signal "GND4")
		(24 "In11.Cu" signal "IN4")
		(26 "In12.Cu" signal "GND5")
		(28 "In13.Cu" signal "IN5")
		(30 "In14.Cu" signal "GND6")
		(32 "In15.Cu" signal "IN6")
		(34 "In16.Cu" signal "GND7")
		(2 "B.Cu" signal "BOTTOM")
		(9 "F.Adhes" user "F.Adhesive")
		(11 "B.Adhes" user "B.Adhesive")
		(13 "F.Paste" user "Package Geometry/Pastemask Top")
		(15 "B.Paste" user "Package Geometry/Pastemask Bottom")
		(5 "F.SilkS" user "Ref Des/Silkscreen Top")
		(7 "B.SilkS" user "Ref Des/Silkscreen Bottom")
		(1 "F.Mask" user "Board Geometry/Soldermask Top")
		(3 "B.Mask" user "Board Geometry/Soldermask Bottom")
		(17 "Dwgs.User" user "User.Drawings")
		(19 "Cmts.User" user "User.Comments")
		(21 "Eco1.User" user "User.Eco1")
		(23 "Eco2.User" user "User.Eco2")
		(25 "Edge.Cuts" user "Board Geometry/Outline")
		(27 "Margin" user)
		(31 "F.CrtYd" user "Package Geometry/Place Bound Top")
		(29 "B.CrtYd" user "Package Geometry/Place Bound Bottom")
		(35 "F.Fab" user "Ref Des/Assembly Top")
		(33 "B.Fab" user "Ref Des/Assembly Bottom")
	)
	(footprint ""
		(layer "F.Cu")
		(at 112.597946 -54.882034 -90)
		(property "Reference" "R6301"
			(at 0 0 270)
			(layer "F.SilkS")
			(hide yes)
			(effects
				(font
					(size 1.27 1.27)
				)
			)
		)
		(property "Value" ""
			(at 0 0 270)
			(layer "F.Fab")
			(effects
				(font
					(size 1.27 1.27)
				)
			)
		)
		(duplicate_pad_numbers_are_jumpers no)
		(fp_line
			(start -0.7874 0.4064)
			(end -0.7874 -0.4064)
			(stroke
				(width 0.1524)
				(type default)
			)
			(layer "F.SilkS")
		)
		(fp_line
			(start 0.7874 0.4064)
			(end -0.7874 0.4064)
			(stroke
				(width 0.1524)
				(type default)
			)
			(layer "F.SilkS")
		)
		(fp_line
			(start -0.7874 -0.4064)
			(end 0.7874 -0.4064)
			(stroke
				(width 0.1524)
				(type default)
			)
			(layer "F.SilkS")
		)
		(fp_line
			(start 0.7874 -0.4064)
			(end 0.7874 0.4064)
			(stroke
				(width 0.1524)
				(type default)
			)
			(layer "F.SilkS")
		)
		(fp_line
			(start -0.67945 0.3048)
			(end -0.67945 -0.305054)
			(stroke
				(width 0.1)
				(type default)
			)
			(layer "F.Fab")
		)
		(fp_line
			(start -0.12065 0.3048)
			(end -0.67945 0.3048)
			(stroke
				(width 0.1)
				(type default)
			)
			(layer "F.Fab")
		)
		(fp_line
			(start 0.120396 0.3048)
			(end 0.120396 0.2794)
			(stroke
				(width 0.1)
				(type default)
			)
			(layer "F.Fab")
		)
		(fp_line
			(start 0.67945 0.3048)
			(end 0.120396 0.3048)
			(stroke
				(width 0.1)
				(type default)
			)
			(layer "F.Fab")
		)
		(fp_line
			(start -0.12065 0.2794)
			(end -0.12065 0.3048)
			(stroke
				(width 0.1)
				(type default)
			)
			(layer "F.Fab")
		)
		(fp_line
			(start 0.120396 0.2794)
			(end -0.12065 0.2794)
			(stroke
				(width 0.1)
				(type default)
			)
			(layer "F.Fab")
		)
		(fp_line
			(start -0.12065 -0.2794)
			(end 0.12065 -0.2794)
			(stroke
				(width 0.1)
				(type default)
			)
			(layer "F.Fab")
		)
		(fp_line
			(start 0.12065 -0.2794)
			(end 0.12065 -0.3048)
			(stroke
				(width 0.1)
				(type default)
			)
			(layer "F.Fab")
		)
		(fp_line
			(start 0.12065 -0.3048)
			(end 0.67945 -0.3048)
			(stroke
				(width 0.1)
				(type default)
			)
			(layer "F.Fab")
		)
		(fp_line
			(start 0.67945 -0.3048)
			(end 0.67945 0.3048)
			(stroke
				(width 0.1)
				(type default)
			)
			(layer "F.Fab")
		)
		(fp_line
			(start -0.67945 -0.305054)
			(end -0.12065 -0.305054)
			(stroke
				(width 0.1)
				(type default)
			)
			(layer "F.Fab")
		)
		(fp_line
			(start -0.12065 -0.305054)
			(end -0.12065 -0.2794)
			(stroke
				(width 0.1)
				(type default)
			)
			(layer "F.Fab")
		)
		(pad "1" smd circle
			(at -0.40005 0 270)
			(size 0 0)
			(layers "F.Cu" "F.Mask" "F.Paste")
			(net "P3V3_AUX")
		)
		(pad "2" smd circle
			(at 0.40005 0 270)
			(size 0 0)
			(layers "F.Cu" "F.Mask" "F.Paste")
			(net "USB_HUB2_TI_OVERCUR3")
		)
	)
	(footprint ""
		(layer "F.Cu")
		(at 198.489824 -96.422718 90)
		(property "Reference" "R1129"
			(at 0 0 90)
			(layer "F.SilkS")
			(hide yes)
			(effects
				(font
					(size 1.27 1.27)
				)
			)
		)
		(property "Value" ""
			(at 0 0 90)
			(layer "F.Fab")
			(effects
				(font
					(size 1.27 1.27)
				)
			)
		)
		(duplicate_pad_numbers_are_jumpers no)
		(fp_line
			(start 0.7874 -0.4064)
			(end 0.7874 0.4064)
			(stroke
				(width 0.1524)
				(type default)
			)
			(layer "F.SilkS")
		)
		(fp_line
			(start -0.7874 -0.4064)
			(end 0.7874 -0.4064)
			(stroke
				(width 0.1524)
				(type default)
			)
			(layer "F.SilkS")
		)
		(fp_line
			(start 0.7874 0.4064)
			(end -0.7874 0.4064)
			(stroke
				(width 0.1524)
				(type default)
			)
			(layer "F.SilkS")
		)
		(fp_line
			(start -0.7874 0.4064)
			(end -0.7874 -0.4064)
			(stroke
				(width 0.1524)
				(type default)
			)
			(layer "F.SilkS")
		)
		(fp_line
			(start -0.12065 -0.305054)
			(end -0.12065 -0.2794)
			(stroke
				(width 0.1)
				(type default)
			)
			(layer "F.Fab")
		)
		(fp_line
			(start -0.67945 -0.305054)
			(end -0.12065 -0.305054)
			(stroke
				(width 0.1)
				(type default)
			)
			(layer "F.Fab")
		)
		(fp_line
			(start 0.67945 -0.3048)
			(end 0.67945 0.3048)
			(stroke
				(width 0.1)
				(type default)
			)
			(layer "F.Fab")
		)
		(fp_line
			(start 0.12065 -0.3048)
			(end 0.67945 -0.3048)
			(stroke
				(width 0.1)
				(type default)
			)
			(layer "F.Fab")
		)
		(fp_line
			(start 0.12065 -0.2794)
			(end 0.12065 -0.3048)
			(stroke
				(width 0.1)
				(type default)
			)
			(layer "F.Fab")
		)
		(fp_line
			(start -0.12065 -0.2794)
			(end 0.12065 -0.2794)
			(stroke
				(width 0.1)
				(type default)
			)
			(layer "F.Fab")
		)
		(fp_line
			(start 0.120396 0.2794)
			(end -0.12065 0.2794)
			(stroke
				(width 0.1)
				(type default)
			)
			(layer "F.Fab")
		)
		(fp_line
			(start -0.12065 0.2794)
			(end -0.12065 0.3048)
			(stroke
				(width 0.1)
				(type default)
			)
			(layer "F.Fab")
		)
		(fp_line
			(start 0.67945 0.3048)
			(end 0.120396 0.3048)
			(stroke
				(width 0.1)
				(type default)
			)
			(layer "F.Fab")
		)
		(fp_line
			(start 0.120396 0.3048)
			(end 0.120396 0.2794)
			(stroke
				(width 0.1)
				(type default)
			)
			(layer "F.Fab")
		)
		(fp_line
			(start -0.12065 0.3048)
			(end -0.67945 0.3048)
			(stroke
				(width 0.1)
				(type default)
			)
			(layer "F.Fab")
		)
		(fp_line
			(start -0.67945 0.3048)
			(end -0.67945 -0.305054)
			(stroke
				(width 0.1)
				(type default)
			)
			(layer "F.Fab")
		)
		(pad "1" smd circle
			(at -0.40005 0 90)
			(size 0 0)
			(layers "F.Cu" "F.Mask" "F.Paste")
			(net "HP_LVC3_OCP_V3_1_P12V_PWRGD")
		)
		(pad "2" smd circle
			(at 0.40005 0 90)
			(size 0 0)
			(layers "F.Cu" "F.Mask" "F.Paste")
			(net "HP_LVC3_OCP_V3_1_P12V_R_PWRGD")
		)
	)
	(footprint ""
		(layer "F.Cu")
		(at 355.915722 -178.813206 180)
		(property "Reference" "PL61"
			(at 3.57124 8.140954 0)
			(unlocked yes)
			(layer "F.SilkS")
			(effects
				(font
					(size 0.7874 0.5842)
					(thickness 0.1524)
				)
				(justify left)
			)
		)
		(property "Value" ""
			(at 0 0 180)
			(layer "F.Fab")
			(effects
				(font
					(size 1.27 1.27)
				)
			)
		)
		(duplicate_pad_numbers_are_jumpers no)
		(fp_line
			(start 3.750056 5.500116)
			(end 3.750056 -5.500116)
			(stroke
				(width 0.1524)
				(type default)
			)
			(layer "F.SilkS")
		)
		(fp_line
			(start 3.750056 -5.500116)
			(end 2.393442 -5.500116)
			(stroke
				(width 0.1524)
				(type default)
			)
			(layer "F.SilkS")
		)
		(fp_line
			(start 2.393442 5.500116)
			(end 3.750056 5.500116)
			(stroke
				(width 0.1524)
				(type default)
			)
			(layer "F.SilkS")
		)
		(fp_line
			(start -2.393442 5.500116)
			(end -3.750056 5.500116)
			(stroke
				(width 0.1524)
				(type default)
			)
			(layer "F.SilkS")
		)
		(fp_line
			(start -3.750056 5.500116)
			(end -3.750056 -5.500116)
			(stroke
				(width 0.1524)
				(type default)
			)
			(layer "F.SilkS")
		)
		(fp_line
			(start -3.750056 -5.500116)
			(end -2.393442 -5.500116)
			(stroke
				(width 0.1524)
				(type default)
			)
			(layer "F.SilkS")
		)
		(fp_poly
			(pts
				(xy -4.149598 -5.301742) (xy -5.165598 -4.793742) (xy -5.165598 -5.809742)
			)
			(stroke
				(width 0)
				(type default)
			)
			(fill yes)
			(layer "F.SilkS")
		)
		(fp_line
			(start 3.750056 5.500116)
			(end 3.750056 -5.500116)
			(stroke
				(width 0.1)
				(type default)
			)
			(layer "F.Fab")
		)
		(fp_line
			(start 3.750056 -5.500116)
			(end -3.750056 -5.500116)
			(stroke
				(width 0.1)
				(type default)
			)
			(layer "F.Fab")
		)
		(fp_line
			(start -3.750056 5.500116)
			(end 3.750056 5.500116)
			(stroke
				(width 0.1)
				(type default)
			)
			(layer "F.Fab")
		)
		(fp_line
			(start -3.750056 -5.500116)
			(end -3.750056 5.500116)
			(stroke
				(width 0.1)
				(type default)
			)
			(layer "F.Fab")
		)
		(fp_poly
			(pts
				(xy -4.9276 -4.757928) (xy -4.9276 -3.741928) (xy -3.9116 -4.249928)
			)
			(stroke
				(width 0)
				(type default)
			)
			(fill yes)
			(layer "F.Fab")
		)
		(pad "1" smd rect
			(at 0 -4.249928 90)
			(size 2.413 4.5212)
			(layers "F.Cu" "F.Mask" "F.Paste")
			(net "SW_PVDDCR_CPU0_P0_SW5")
		)
		(pad "2" smd rect
			(at 0 -1.175004 90)
			(size 1.3716 4.5212)
			(layers "F.Cu" "F.Mask" "F.Paste")
			(net "IND_CPU0_P0_CPL6")
		)
		(pad "3" smd rect
			(at 0 1.175004 90)
			(size 1.3716 4.5212)
			(layers "F.Cu" "F.Mask" "F.Paste")
			(net "IND_CPU0_P0_CPL5")
		)
		(pad "4" smd rect
			(at 0 4.249928 90)
			(size 2.413 4.5212)
			(layers "F.Cu" "F.Mask" "F.Paste")
			(net "PVDDCR_CPU0_P0")
		)
	)
	(footprint ""
		(layer "F.Cu")
		(at 457.329794 -46.264576 -90)
		(property "Reference" "PR830"
			(at 0 0 270)
			(layer "F.SilkS")
			(hide yes)
			(effects
				(font
					(size 1.27 1.27)
				)
			)
		)
		(property "Value" ""
			(at 0 0 270)
			(layer "F.Fab")
			(effects
				(font
					(size 1.27 1.27)
				)
			)
		)
		(duplicate_pad_numbers_are_jumpers no)
		(fp_line
			(start -0.7874 0.4064)
			(end -0.7874 -0.4064)
			(stroke
				(width 0.1524)
				(type default)
			)
			(layer "F.SilkS")
		)
		(fp_line
			(start 0.7874 0.4064)
			(end -0.7874 0.4064)
			(stroke
				(width 0.1524)
				(type default)
			)
			(layer "F.SilkS")
		)
		(fp_line
			(start -0.7874 -0.4064)
			(end 0.7874 -0.4064)
			(stroke
				(width 0.1524)
				(type default)
			)
			(layer "F.SilkS")
		)
		(fp_line
			(start 0.7874 -0.4064)
			(end 0.7874 0.4064)
			(stroke
				(width 0.1524)
				(type default)
			)
			(layer "F.SilkS")
		)
		(fp_line
			(start -0.67945 0.3048)
			(end -0.67945 -0.305054)
			(stroke
				(width 0.1)
				(type default)
			)
			(layer "F.Fab")
		)
		(fp_line
			(start -0.12065 0.3048)
			(end -0.67945 0.3048)
			(stroke
				(width 0.1)
				(type default)
			)
			(layer "F.Fab")
		)
		(fp_line
			(start 0.120396 0.3048)
			(end 0.120396 0.2794)
			(stroke
				(width 0.1)
				(type default)
			)
			(layer "F.Fab")
		)
		(fp_line
			(start 0.67945 0.3048)
			(end 0.120396 0.3048)
			(stroke
				(width 0.1)
				(type default)
			)
			(layer "F.Fab")
		)
		(fp_line
			(start -0.12065 0.2794)
			(end -0.12065 0.3048)
			(stroke
				(width 0.1)
				(type default)
			)
			(layer "F.Fab")
		)
		(fp_line
			(start 0.120396 0.2794)
			(end -0.12065 0.2794)
			(stroke
				(width 0.1)
				(type default)
			)
			(layer "F.Fab")
		)
		(fp_line
			(start -0.12065 -0.2794)
			(end 0.12065 -0.2794)
			(stroke
				(width 0.1)
				(type default)
			)
			(layer "F.Fab")
		)
		(fp_line
			(start 0.12065 -0.2794)
			(end 0.12065 -0.3048)
			(stroke
				(width 0.1)
				(type default)
			)
			(layer "F.Fab")
		)
		(fp_line
			(start 0.12065 -0.3048)
			(end 0.67945 -0.3048)
			(stroke
				(width 0.1)
				(type default)
			)
			(layer "F.Fab")
		)
		(fp_line
			(start 0.67945 -0.3048)
			(end 0.67945 0.3048)
			(stroke
				(width 0.1)
				(type default)
			)
			(layer "F.Fab")
		)
		(fp_line
			(start -0.67945 -0.305054)
			(end -0.12065 -0.305054)
			(stroke
				(width 0.1)
				(type default)
			)
			(layer "F.Fab")
		)
		(fp_line
			(start -0.12065 -0.305054)
			(end -0.12065 -0.2794)
			(stroke
				(width 0.1)
				(type default)
			)
			(layer "F.Fab")
		)
		(pad "1" smd circle
			(at -0.40005 0 270)
			(size 0 0)
			(layers "F.Cu" "F.Mask" "F.Paste")
			(net "P3V3_AUX_FB")
		)
		(pad "2" smd circle
			(at 0.40005 0 270)
			(size 0 0)
			(layers "F.Cu" "F.Mask" "F.Paste")
			(net "GND")
		)
	)
	(footprint ""
		(layer "F.Cu")
		(at 331.793342 -393.96416)
		(property "Reference" "R1028"
			(at 0 0 0)
			(layer "F.SilkS")
			(hide yes)
			(effects
				(font
					(size 1.27 1.27)
				)
			)
		)
		(property "Value" ""
			(at 0 0 0)
			(layer "F.Fab")
			(effects
				(font
					(size 1.27 1.27)
				)
			)
		)
		(duplicate_pad_numbers_are_jumpers no)
		(fp_line
			(start -0.32512 -0.175006)
			(end 0.32512 -0.175006)
			(stroke
				(width 0.1)
				(type default)
			)
			(layer "F.Fab")
		)
		(fp_line
			(start -0.32512 0.175006)
			(end -0.32512 -0.175006)
			(stroke
				(width 0.1)
				(type default)
			)
			(layer "F.Fab")
		)
		(fp_line
			(start 0.32512 -0.175006)
			(end 0.32512 0.175006)
			(stroke
				(width 0.1)
				(type default)
			)
			(layer "F.Fab")
		)
		(fp_line
			(start 0.32512 0.175006)
			(end -0.32512 0.175006)
			(stroke
				(width 0.1)
				(type default)
			)
			(layer "F.Fab")
		)
		(pad "1" smd rect
			(at -0.2667 0)
			(size 0.3048 0.381)
			(layers "F.Cu" "F.Mask" "F.Paste")
			(net "GPIO2_RT_CPU0_P1")
		)
		(pad "2" smd rect
			(at 0.2667 0 180)
			(size 0.3048 0.381)
			(layers "F.Cu" "F.Mask" "F.Paste")
			(net "GND")
		)
	)
	(footprint ""
		(layer "F.Cu")
		(at 173.9392 -94.833948 -90)
		(property "Reference" "R6009"
			(at 0 0 270)
			(layer "F.SilkS")
			(hide yes)
			(effects
				(font
					(size 1.27 1.27)
				)
			)
		)
		(property "Value" ""
			(at 0 0 270)
			(layer "F.Fab")
			(effects
				(font
					(size 1.27 1.27)
				)
			)
		)
		(duplicate_pad_numbers_are_jumpers no)
		(fp_line
			(start -0.7874 0.4064)
			(end -0.7874 -0.4064)
			(stroke
				(width 0.1524)
				(type default)
			)
			(layer "F.SilkS")
		)
		(fp_line
			(start 0.7874 0.4064)
			(end -0.7874 0.4064)
			(stroke
				(width 0.1524)
				(type default)
			)
			(layer "F.SilkS")
		)
		(fp_line
			(start -0.7874 -0.4064)
			(end 0.7874 -0.4064)
			(stroke
				(width 0.1524)
				(type default)
			)
			(layer "F.SilkS")
		)
		(fp_line
			(start 0.7874 -0.4064)
			(end 0.7874 0.4064)
			(stroke
				(width 0.1524)
				(type default)
			)
			(layer "F.SilkS")
		)
		(fp_line
			(start -0.67945 0.3048)
			(end -0.67945 -0.305054)
			(stroke
				(width 0.1)
				(type default)
			)
			(layer "F.Fab")
		)
		(fp_line
			(start -0.12065 0.3048)
			(end -0.67945 0.3048)
			(stroke
				(width 0.1)
				(type default)
			)
			(layer "F.Fab")
		)
		(fp_line
			(start 0.120396 0.3048)
			(end 0.120396 0.2794)
			(stroke
				(width 0.1)
				(type default)
			)
			(layer "F.Fab")
		)
		(fp_line
			(start 0.67945 0.3048)
			(end 0.120396 0.3048)
			(stroke
				(width 0.1)
				(type default)
			)
			(layer "F.Fab")
		)
		(fp_line
			(start -0.12065 0.2794)
			(end -0.12065 0.3048)
			(stroke
				(width 0.1)
				(type default)
			)
			(layer "F.Fab")
		)
		(fp_line
			(start 0.120396 0.2794)
			(end -0.12065 0.2794)
			(stroke
				(width 0.1)
				(type default)
			)
			(layer "F.Fab")
		)
		(fp_line
			(start -0.12065 -0.2794)
			(end 0.12065 -0.2794)
			(stroke
				(width 0.1)
				(type default)
			)
			(layer "F.Fab")
		)
		(fp_line
			(start 0.12065 -0.2794)
			(end 0.12065 -0.3048)
			(stroke
				(width 0.1)
				(type default)
			)
			(layer "F.Fab")
		)
		(fp_line
			(start 0.12065 -0.3048)
			(end 0.67945 -0.3048)
			(stroke
				(width 0.1)
				(type default)
			)
			(layer "F.Fab")
		)
		(fp_line
			(start 0.67945 -0.3048)
			(end 0.67945 0.3048)
			(stroke
				(width 0.1)
				(type default)
			)
			(layer "F.Fab")
		)
		(fp_line
			(start -0.67945 -0.305054)
			(end -0.12065 -0.305054)
			(stroke
				(width 0.1)
				(type default)
			)
			(layer "F.Fab")
		)
		(fp_line
			(start -0.12065 -0.305054)
			(end -0.12065 -0.2794)
			(stroke
				(width 0.1)
				(type default)
			)
			(layer "F.Fab")
		)
		(pad "1" smd circle
			(at -0.40005 0 270)
			(size 0 0)
			(layers "F.Cu" "F.Mask" "F.Paste")
			(net "SGPIO_SCM_CLK_<0>")
		)
		(pad "2" smd circle
			(at 0.40005 0 270)
			(size 0 0)
			(layers "F.Cu" "F.Mask" "F.Paste")
			(net "SGPIO_SCM_CLK_R_<0>")
		)
	)
	(footprint ""
		(layer "F.Cu")
		(at 104.409748 -385.5212 90)
		(property "Reference" "R735"
			(at 0 0 90)
			(layer "F.SilkS")
			(hide yes)
			(effects
				(font
					(size 1.27 1.27)
				)
			)
		)
		(property "Value" ""
			(at 0 0 90)
			(layer "F.Fab")
			(effects
				(font
					(size 1.27 1.27)
				)
			)
		)
		(duplicate_pad_numbers_are_jumpers no)
		(fp_line
			(start 0.32512 -0.175006)
			(end 0.32512 0.175006)
			(stroke
				(width 0.1)
				(type default)
			)
			(layer "F.Fab")
		)
		(fp_line
			(start -0.32512 -0.175006)
			(end 0.32512 -0.175006)
			(stroke
				(width 0.1)
				(type default)
			)
			(layer "F.Fab")
		)
		(fp_line
			(start 0.32512 0.175006)
			(end -0.32512 0.175006)
			(stroke
				(width 0.1)
				(type default)
			)
			(layer "F.Fab")
		)
		(fp_line
			(start -0.32512 0.175006)
			(end -0.32512 -0.175006)
			(stroke
				(width 0.1)
				(type default)
			)
			(layer "F.Fab")
		)
		(pad "1" smd rect
			(at -0.2667 0 90)
			(size 0.3048 0.381)
			(layers "F.Cu" "F.Mask" "F.Paste")
			(net "P1V8_CPU1_RT_1D")
		)
		(pad "2" smd rect
			(at 0.2667 0 270)
			(size 0.3048 0.381)
			(layers "F.Cu" "F.Mask" "F.Paste")
			(net "RT_CPU1_P1_ADDR3")
		)
	)
	(footprint ""
		(layer "F.Cu")
		(at 291.652706 -140.770864 180)
		(property "Reference" ""
			(at 0 0 180)
			(layer "F.SilkS")
			(hide yes)
			(effects
				(font
					(size 1.27 1.27)
				)
			)
		)
		(property "Value" ""
			(at 0 0 180)
			(layer "F.Fab")
			(effects
				(font
					(size 1.27 1.27)
				)
			)
		)
		(duplicate_pad_numbers_are_jumpers no)
		(pad "1" smd circle
			(at 0 0 180)
			(size 0.9906 0.9906)
			(layers "F.Cu" "F.Mask" "F.Paste")
			(net "Net_2237")
		)
		(zone
			(layer "F.Cu")
			(hatch none 0.5)
			(connect_pads
				(clearance 0)
			)
			(min_thickness 0.25)
			(keepout
				(tracks not_allowed)
				(vias allowed)
				(pads allowed)
				(copperpour not_allowed)
				(footprints allowed)
			)
			(placement
				(enabled no)
				(sheetname "")
			)
			(fill
				(thermal_gap 0.5)
				(thermal_bridge_width 0.5)
				(island_removal_mode 0)
			)
			(polygon
				(pts
					(arc
						(start 293.278306 -140.770864)
						(mid 290.027106 -140.770864)
						(end 293.278306 -140.770864)
					)
				)
			)
		)
	)
)
